(kicad_pcb
	(version 20260206)
	(generator "pcbnew")
	(generator_version "10.0")
	(general
		(thickness 1.6)
		(legacy_teardrops no)
	)
	(paper "A4")
	(title_block
		(title "v1-chassis-manager — T6M_CM_d_v01_1031_1645.brd")
		(comment 1 "Open CloudServer (Microsoft) / footprints 1953-1962 of 2512")
	)
	(layers
		(0 "F.Cu" signal "TOP")
		(4 "In1.Cu" signal "GND1")
		(6 "In2.Cu" signal "IN1")
		(8 "In3.Cu" signal "VCC1")
		(10 "In4.Cu" signal "VCC2")
		(12 "In5.Cu" signal "GND2")
		(14 "In6.Cu" signal "IN2")
		(16 "In7.Cu" signal "IN3")
		(18 "In8.Cu" signal "GND3")
		(2 "B.Cu" signal "BOTTOM")
		(9 "F.Adhes" user "F.Adhesive")
		(11 "B.Adhes" user "B.Adhesive")
		(13 "F.Paste" user "Package Geometry/Pastemask Top")
		(15 "B.Paste" user "Package Geometry/Pastemask Bottom")
		(5 "F.SilkS" user "Ref Des/Silkscreen Top")
		(7 "B.SilkS" user "Ref Des/Silkscreen Bottom")
		(1 "F.Mask" user "Board Geometry/Soldermask Top")
		(3 "B.Mask" user "Board Geometry/Soldermask Bottom")
		(17 "Dwgs.User" user "User.Drawings")
		(19 "Cmts.User" user "User.Comments")
		(21 "Eco1.User" user "User.Eco1")
		(23 "Eco2.User" user "User.Eco2")
		(25 "Edge.Cuts" user "Board Geometry/Outline")
		(27 "Margin" user)
		(31 "F.CrtYd" user "Package Geometry/Place Bound Top")
		(29 "B.CrtYd" user "Package Geometry/Place Bound Bottom")
		(35 "F.Fab" user "Ref Des/Assembly Top")
		(33 "B.Fab" user "Ref Des/Assembly Bottom")
	)
	(footprint ""
		(layer "B.Cu")
		(at 66.581528 -62.855856 -90)
		(property "Reference" "C114"
			(at 5.118862 -0.922782 270)
			(unlocked yes)
			(layer "B.SilkS")
			(effects
				(font
					(size 0.7874 0.5842)
					(thickness 0.1524)
				)
				(justify left mirror)
			)
		)
		(property "Value" ""
			(at 0 0 90)
			(layer "B.Fab")
			(effects
				(font
					(size 1.27 1.27)
				)
				(justify mirror)
			)
		)
		(duplicate_pad_numbers_are_jumpers no)
		(fp_line
			(start -0.7874 0.4064)
			(end 0.7874 0.4064)
			(stroke
				(width 0.1524)
				(type default)
			)
			(layer "B.SilkS")
		)
		(fp_line
			(start 0.7874 0.4064)
			(end 0.7874 -0.4064)
			(stroke
				(width 0.1524)
				(type default)
			)
			(layer "B.SilkS")
		)
		(fp_line
			(start 0 0.381)
			(end 0 -0.381)
			(stroke
				(width 0.1524)
				(type default)
			)
			(layer "B.SilkS")
		)
		(fp_line
			(start -0.7874 -0.4064)
			(end -0.7874 0.4064)
			(stroke
				(width 0.1524)
				(type default)
			)
			(layer "B.SilkS")
		)
		(fp_line
			(start 0.7874 -0.4064)
			(end -0.7874 -0.4064)
			(stroke
				(width 0.1524)
				(type default)
			)
			(layer "B.SilkS")
		)
		(fp_poly
			(pts
				(xy 0.5334 0.254) (xy 0.635 0.254) (xy 0.635 0.2286) (xy 0.635 -0.254) (xy 0.5334 -0.254) (xy 0.5334 -0.2794)
				(xy -0.5334 -0.2794) (xy -0.5334 -0.254) (xy -0.635 -0.254) (xy -0.635 0.254) (xy -0.5334 0.254)
				(xy -0.5334 0.2794) (xy 0.508 0.2794) (xy 0.5334 0.2794)
			)
			(stroke
				(width 0)
				(type default)
			)
			(fill no)
			(layer "B.CrtYd")
		)
		(pad "1" smd rect
			(at -0.40005 0 90)
			(size 0.4572 0.508)
			(layers "B.Cu" "B.Mask" "B.Paste")
			(net "PV_VDDR_NODE1")
		)
		(pad "2" smd rect
			(at 0.40005 0 90)
			(size 0.4572 0.508)
			(layers "B.Cu" "B.Mask" "B.Paste")
			(net "GND")
		)
	)
	(footprint ""
		(layer "B.Cu")
		(at 55.038498 -96.696784 90)
		(property "Reference" "R53"
			(at 6.405118 -4.364228 270)
			(unlocked yes)
			(layer "B.SilkS")
			(effects
				(font
					(size 0.7874 0.5842)
					(thickness 0.1524)
				)
				(justify left mirror)
			)
		)
		(property "Value" ""
			(at 0 0 90)
			(layer "B.Fab")
			(effects
				(font
					(size 1.27 1.27)
				)
				(justify mirror)
			)
		)
		(duplicate_pad_numbers_are_jumpers no)
		(fp_line
			(start 0.7874 -0.4064)
			(end -0.7874 -0.4064)
			(stroke
				(width 0.1524)
				(type default)
			)
			(layer "B.SilkS")
		)
		(fp_line
			(start -0.7874 -0.4064)
			(end -0.7874 0.4064)
			(stroke
				(width 0.1524)
				(type default)
			)
			(layer "B.SilkS")
		)
		(fp_line
			(start 0.7874 0.4064)
			(end 0.7874 -0.4064)
			(stroke
				(width 0.1524)
				(type default)
			)
			(layer "B.SilkS")
		)
		(fp_line
			(start -0.7874 0.4064)
			(end 0.7874 0.4064)
			(stroke
				(width 0.1524)
				(type default)
			)
			(layer "B.SilkS")
		)
		(fp_poly
			(pts
				(xy 0.508 0.2794) (xy 0.508 0.2286) (xy 0.635 0.2286) (xy 0.635 -0.254) (xy 0.5334 -0.254) (xy 0.5334 -0.2794)
				(xy -0.5334 -0.2794) (xy -0.5334 -0.254) (xy -0.635 -0.254) (xy -0.635 0.254) (xy -0.5334 0.254)
				(xy -0.5334 0.2794)
			)
			(stroke
				(width 0)
				(type default)
			)
			(fill no)
			(layer "B.CrtYd")
		)
		(pad "1" smd rect
			(at -0.40005 0 270)
			(size 0.4572 0.508)
			(layers "B.Cu" "B.Mask" "B.Paste")
			(net "PU_CPU_NODE1_DFX_GPIO_GRP1_3")
		)
		(pad "2" smd rect
			(at 0.40005 0 270)
			(size 0.4572 0.508)
			(layers "B.Cu" "B.Mask" "B.Paste")
			(net "P1V8_NODE1")
		)
	)
	(footprint ""
		(layer "B.Cu")
		(at 122.0978 -43.716702)
		(property "Reference" "R183"
			(at -2.808732 0.03429 0)
			(unlocked yes)
			(layer "B.SilkS")
			(effects
				(font
					(size 0.7874 0.5842)
					(thickness 0.1524)
				)
				(justify left mirror)
			)
		)
		(property "Value" ""
			(at 0 0 0)
			(layer "B.Fab")
			(effects
				(font
					(size 1.27 1.27)
				)
				(justify mirror)
			)
		)
		(duplicate_pad_numbers_are_jumpers no)
		(fp_line
			(start -0.7874 -0.4064)
			(end -0.7874 0.4064)
			(stroke
				(width 0.1524)
				(type default)
			)
			(layer "B.SilkS")
		)
		(fp_line
			(start -0.7874 0.4064)
			(end 0.7874 0.4064)
			(stroke
				(width 0.1524)
				(type default)
			)
			(layer "B.SilkS")
		)
		(fp_line
			(start 0.7874 -0.4064)
			(end -0.7874 -0.4064)
			(stroke
				(width 0.1524)
				(type default)
			)
			(layer "B.SilkS")
		)
		(fp_line
			(start 0.7874 0.4064)
			(end 0.7874 -0.4064)
			(stroke
				(width 0.1524)
				(type default)
			)
			(layer "B.SilkS")
		)
		(fp_poly
			(pts
				(xy 0.508 0.2794) (xy 0.508 0.2286) (xy 0.635 0.2286) (xy 0.635 -0.254) (xy 0.5334 -0.254) (xy 0.5334 -0.2794)
				(xy -0.5334 -0.2794) (xy -0.5334 -0.254) (xy -0.635 -0.254) (xy -0.635 0.254) (xy -0.5334 0.254)
				(xy -0.5334 0.2794)
			)
			(stroke
				(width 0)
				(type default)
			)
			(fill no)
			(layer "B.CrtYd")
		)
		(pad "1" smd rect
			(at -0.40005 0 180)
			(size 0.4572 0.508)
			(layers "B.Cu" "B.Mask" "B.Paste")
			(net "LPC_CPU_NODE1_LAD1")
		)
		(pad "2" smd rect
			(at 0.40005 0 180)
			(size 0.4572 0.508)
			(layers "B.Cu" "B.Mask" "B.Paste")
			(net "LPC_CPU_NODE1_LAD1_SIO")
		)
	)
	(footprint ""
		(layer "B.Cu")
		(at 75.0062 -31.72714 180)
		(property "Reference" "C144"
			(at -1.788922 -2.09804 0)
			(unlocked yes)
			(layer "B.SilkS")
			(effects
				(font
					(size 0.7874 0.5842)
					(thickness 0.1524)
				)
				(justify left mirror)
			)
		)
		(property "Value" ""
			(at 0 0 0)
			(layer "B.Fab")
			(effects
				(font
					(size 1.27 1.27)
				)
				(justify mirror)
			)
		)
		(duplicate_pad_numbers_are_jumpers no)
		(fp_line
			(start 0.7874 0.4064)
			(end 0.7874 -0.4064)
			(stroke
				(width 0.1524)
				(type default)
			)
			(layer "B.SilkS")
		)
		(fp_line
			(start 0.7874 -0.4064)
			(end -0.7874 -0.4064)
			(stroke
				(width 0.1524)
				(type default)
			)
			(layer "B.SilkS")
		)
		(fp_line
			(start 0 0.381)
			(end 0 -0.381)
			(stroke
				(width 0.1524)
				(type default)
			)
			(layer "B.SilkS")
		)
		(fp_line
			(start -0.7874 0.4064)
			(end 0.7874 0.4064)
			(stroke
				(width 0.1524)
				(type default)
			)
			(layer "B.SilkS")
		)
		(fp_line
			(start -0.7874 -0.4064)
			(end -0.7874 0.4064)
			(stroke
				(width 0.1524)
				(type default)
			)
			(layer "B.SilkS")
		)
		(fp_poly
			(pts
				(xy 0.5334 0.254) (xy 0.635 0.254) (xy 0.635 0.2286) (xy 0.635 -0.254) (xy 0.5334 -0.254) (xy 0.5334 -0.2794)
				(xy -0.5334 -0.2794) (xy -0.5334 -0.254) (xy -0.635 -0.254) (xy -0.635 0.254) (xy -0.5334 0.254)
				(xy -0.5334 0.2794) (xy 0.508 0.2794) (xy 0.5334 0.2794)
			)
			(stroke
				(width 0)
				(type default)
			)
			(fill no)
			(layer "B.CrtYd")
		)
		(pad "1" smd rect
			(at -0.40005 0)
			(size 0.4572 0.508)
			(layers "B.Cu" "B.Mask" "B.Paste")
			(net "PV_VDDR_NODE1")
		)
		(pad "2" smd rect
			(at 0.40005 0)
			(size 0.4572 0.508)
			(layers "B.Cu" "B.Mask" "B.Paste")
			(net "GND")
		)
	)
	(footprint ""
		(layer "B.Cu")
		(at 53.95976 -188.126624 -90)
		(property "Reference" "C673"
			(at -4.276598 -0.103124 270)
			(unlocked yes)
			(layer "B.SilkS")
			(effects
				(font
					(size 0.7874 0.5842)
					(thickness 0.1524)
				)
				(justify left mirror)
			)
		)
		(property "Value" ""
			(at 0 0 90)
			(layer "B.Fab")
			(effects
				(font
					(size 1.27 1.27)
				)
				(justify mirror)
			)
		)
		(duplicate_pad_numbers_are_jumpers no)
		(fp_line
			(start -0.7874 0.4064)
			(end 0.7874 0.4064)
			(stroke
				(width 0.1524)
				(type default)
			)
			(layer "B.SilkS")
		)
		(fp_line
			(start 0.7874 0.4064)
			(end 0.7874 -0.4064)
			(stroke
				(width 0.1524)
				(type default)
			)
			(layer "B.SilkS")
		)
		(fp_line
			(start 0 0.381)
			(end 0 -0.381)
			(stroke
				(width 0.1524)
				(type default)
			)
			(layer "B.SilkS")
		)
		(fp_line
			(start -0.7874 -0.4064)
			(end -0.7874 0.4064)
			(stroke
				(width 0.1524)
				(type default)
			)
			(layer "B.SilkS")
		)
		(fp_line
			(start 0.7874 -0.4064)
			(end -0.7874 -0.4064)
			(stroke
				(width 0.1524)
				(type default)
			)
			(layer "B.SilkS")
		)
		(fp_poly
			(pts
				(xy 0.5334 0.254) (xy 0.635 0.254) (xy 0.635 0.2286) (xy 0.635 -0.254) (xy 0.5334 -0.254) (xy 0.5334 -0.2794)
				(xy -0.5334 -0.2794) (xy -0.5334 -0.254) (xy -0.635 -0.254) (xy -0.635 0.254) (xy -0.5334 0.254)
				(xy -0.5334 0.2794) (xy 0.508 0.2794) (xy 0.5334 0.2794)
			)
			(stroke
				(width 0)
				(type default)
			)
			(fill no)
			(layer "B.CrtYd")
		)
		(pad "1" smd rect
			(at -0.40005 0 90)
			(size 0.4572 0.508)
			(layers "B.Cu" "B.Mask" "B.Paste")
			(net "UART_T1_NODE1_TXD_R")
		)
		(pad "2" smd rect
			(at 0.40005 0 90)
			(size 0.4572 0.508)
			(layers "B.Cu" "B.Mask" "B.Paste")
			(net "GND")
		)
	)
	(footprint ""
		(layer "B.Cu")
		(at 37.92474 -145.56867)
		(property "Reference" "R551"
			(at -2.549652 0.339852 0)
			(unlocked yes)
			(layer "B.SilkS")
			(effects
				(font
					(size 0.7874 0.5842)
					(thickness 0.1524)
				)
				(justify left mirror)
			)
		)
		(property "Value" ""
			(at 0 0 0)
			(layer "B.Fab")
			(effects
				(font
					(size 1.27 1.27)
				)
				(justify mirror)
			)
		)
		(duplicate_pad_numbers_are_jumpers no)
		(fp_line
			(start -0.7874 -0.4064)
			(end -0.7874 0.4064)
			(stroke
				(width 0.1524)
				(type default)
			)
			(layer "B.SilkS")
		)
		(fp_line
			(start -0.7874 0.4064)
			(end 0.7874 0.4064)
			(stroke
				(width 0.1524)
				(type default)
			)
			(layer "B.SilkS")
		)
		(fp_line
			(start 0.7874 -0.4064)
			(end -0.7874 -0.4064)
			(stroke
				(width 0.1524)
				(type default)
			)
			(layer "B.SilkS")
		)
		(fp_line
			(start 0.7874 0.4064)
			(end 0.7874 -0.4064)
			(stroke
				(width 0.1524)
				(type default)
			)
			(layer "B.SilkS")
		)
		(fp_poly
			(pts
				(xy 0.508 0.2794) (xy 0.508 0.2286) (xy 0.635 0.2286) (xy 0.635 -0.254) (xy 0.5334 -0.254) (xy 0.5334 -0.2794)
				(xy -0.5334 -0.2794) (xy -0.5334 -0.254) (xy -0.635 -0.254) (xy -0.635 0.254) (xy -0.5334 0.254)
				(xy -0.5334 0.2794)
			)
			(stroke
				(width 0)
				(type default)
			)
			(fill no)
			(layer "B.CrtYd")
		)
		(pad "1" smd rect
			(at -0.40005 0 180)
			(size 0.4572 0.508)
			(layers "B.Cu" "B.Mask" "B.Paste")
			(net "P3V3_NODE1")
		)
		(pad "2" smd rect
			(at 0.40005 0 180)
			(size 0.4572 0.508)
			(layers "B.Cu" "B.Mask" "B.Paste")
			(net "LAN1_DIS_REG10")
		)
	)
	(footprint ""
		(layer "B.Cu")
		(at 60.057538 -82.325718)
		(property "Reference" "C40"
			(at -13.458698 30.852872 0)
			(unlocked yes)
			(layer "B.SilkS")
			(effects
				(font
					(size 0.7874 0.5842)
					(thickness 0.1524)
				)
				(justify left mirror)
			)
		)
		(property "Value" ""
			(at 0 0 0)
			(layer "B.Fab")
			(effects
				(font
					(size 1.27 1.27)
				)
				(justify mirror)
			)
		)
		(duplicate_pad_numbers_are_jumpers no)
		(fp_line
			(start -0.7874 -0.4064)
			(end -0.7874 0.4064)
			(stroke
				(width 0.1524)
				(type default)
			)
			(layer "B.SilkS")
		)
		(fp_line
			(start -0.7874 0.4064)
			(end 0.7874 0.4064)
			(stroke
				(width 0.1524)
				(type default)
			)
			(layer "B.SilkS")
		)
		(fp_line
			(start 0 0.381)
			(end 0 -0.381)
			(stroke
				(width 0.1524)
				(type default)
			)
			(layer "B.SilkS")
		)
		(fp_line
			(start 0.7874 -0.4064)
			(end -0.7874 -0.4064)
			(stroke
				(width 0.1524)
				(type default)
			)
			(layer "B.SilkS")
		)
		(fp_line
			(start 0.7874 0.4064)
			(end 0.7874 -0.4064)
			(stroke
				(width 0.1524)
				(type default)
			)
			(layer "B.SilkS")
		)
		(fp_poly
			(pts
				(xy 0.5334 0.254) (xy 0.635 0.254) (xy 0.635 0.2286) (xy 0.635 -0.254) (xy 0.5334 -0.254) (xy 0.5334 -0.2794)
				(xy -0.5334 -0.2794) (xy -0.5334 -0.254) (xy -0.635 -0.254) (xy -0.635 0.254) (xy -0.5334 0.254)
				(xy -0.5334 0.2794) (xy 0.508 0.2794) (xy 0.5334 0.2794)
			)
			(stroke
				(width 0)
				(type default)
			)
			(fill no)
			(layer "B.CrtYd")
		)
		(pad "1" smd rect
			(at -0.40005 0 180)
			(size 0.4572 0.508)
			(layers "B.Cu" "B.Mask" "B.Paste")
			(net "P3V3_NODE1")
		)
		(pad "2" smd rect
			(at 0.40005 0 180)
			(size 0.4572 0.508)
			(layers "B.Cu" "B.Mask" "B.Paste")
			(net "GND")
		)
	)
	(footprint ""
		(layer "B.Cu")
		(at 174.616872 -159.346138 -90)
		(property "Reference" "C523"
			(at -2.561844 0.00762 270)
			(unlocked yes)
			(layer "B.SilkS")
			(effects
				(font
					(size 0.7874 0.5842)
					(thickness 0.1524)
				)
				(justify left mirror)
			)
		)
		(property "Value" ""
			(at 0 0 90)
			(layer "B.Fab")
			(effects
				(font
					(size 1.27 1.27)
				)
				(justify mirror)
			)
		)
		(duplicate_pad_numbers_are_jumpers no)
		(fp_line
			(start -0.7874 0.4064)
			(end 0.7874 0.4064)
			(stroke
				(width 0.1524)
				(type default)
			)
			(layer "B.SilkS")
		)
		(fp_line
			(start 0.7874 0.4064)
			(end 0.7874 -0.4064)
			(stroke
				(width 0.1524)
				(type default)
			)
			(layer "B.SilkS")
		)
		(fp_line
			(start 0 0.381)
			(end 0 -0.381)
			(stroke
				(width 0.1524)
				(type default)
			)
			(layer "B.SilkS")
		)
		(fp_line
			(start -0.7874 -0.4064)
			(end -0.7874 0.4064)
			(stroke
				(width 0.1524)
				(type default)
			)
			(layer "B.SilkS")
		)
		(fp_line
			(start 0.7874 -0.4064)
			(end -0.7874 -0.4064)
			(stroke
				(width 0.1524)
				(type default)
			)
			(layer "B.SilkS")
		)
		(fp_poly
			(pts
				(xy 0.5334 0.254) (xy 0.635 0.254) (xy 0.635 0.2286) (xy 0.635 -0.254) (xy 0.5334 -0.254) (xy 0.5334 -0.2794)
				(xy -0.5334 -0.2794) (xy -0.5334 -0.254) (xy -0.635 -0.254) (xy -0.635 0.254) (xy -0.5334 0.254)
				(xy -0.5334 0.2794) (xy 0.508 0.2794) (xy 0.5334 0.2794)
			)
			(stroke
				(width 0)
				(type default)
			)
			(fill no)
			(layer "B.CrtYd")
		)
		(pad "1" smd rect
			(at -0.40005 0 90)
			(size 0.4572 0.508)
			(layers "B.Cu" "B.Mask" "B.Paste")
			(net "P1V9_LAN2")
		)
		(pad "2" smd rect
			(at 0.40005 0 90)
			(size 0.4572 0.508)
			(layers "B.Cu" "B.Mask" "B.Paste")
			(net "GND")
		)
	)
	(footprint ""
		(layer "B.Cu")
		(at 62.18301 -132.007356 180)
		(property "Reference" "C273"
			(at 40.635428 -52.99202 0)
			(unlocked yes)
			(layer "B.SilkS")
			(effects
				(font
					(size 0.7874 0.5842)
					(thickness 0.1524)
				)
				(justify left mirror)
			)
		)
		(property "Value" ""
			(at 0 0 0)
			(layer "B.Fab")
			(effects
				(font
					(size 1.27 1.27)
				)
				(justify mirror)
			)
		)
		(duplicate_pad_numbers_are_jumpers no)
		(fp_line
			(start 0.7874 0.4064)
			(end 0.7874 -0.4064)
			(stroke
				(width 0.1524)
				(type default)
			)
			(layer "B.SilkS")
		)
		(fp_line
			(start 0.7874 -0.4064)
			(end -0.7874 -0.4064)
			(stroke
				(width 0.1524)
				(type default)
			)
			(layer "B.SilkS")
		)
		(fp_line
			(start 0 0.381)
			(end 0 -0.381)
			(stroke
				(width 0.1524)
				(type default)
			)
			(layer "B.SilkS")
		)
		(fp_line
			(start -0.7874 0.4064)
			(end 0.7874 0.4064)
			(stroke
				(width 0.1524)
				(type default)
			)
			(layer "B.SilkS")
		)
		(fp_line
			(start -0.7874 -0.4064)
			(end -0.7874 0.4064)
			(stroke
				(width 0.1524)
				(type default)
			)
			(layer "B.SilkS")
		)
		(fp_poly
			(pts
				(xy 0.5334 0.254) (xy 0.635 0.254) (xy 0.635 0.2286) (xy 0.635 -0.254) (xy 0.5334 -0.254) (xy 0.5334 -0.2794)
				(xy -0.5334 -0.2794) (xy -0.5334 -0.254) (xy -0.635 -0.254) (xy -0.635 0.254) (xy -0.5334 0.254)
				(xy -0.5334 0.2794) (xy 0.508 0.2794) (xy 0.5334 0.2794)
			)
			(stroke
				(width 0)
				(type default)
			)
			(fill no)
			(layer "B.CrtYd")
		)
		(pad "1" smd rect
			(at -0.40005 0)
			(size 0.4572 0.508)
			(layers "B.Cu" "B.Mask" "B.Paste")
			(net "GND")
		)
		(pad "2" smd rect
			(at 0.40005 0)
			(size 0.4572 0.508)
			(layers "B.Cu" "B.Mask" "B.Paste")
			(net "P1V538_BMC_NODE1")
		)
	)
	(footprint ""
		(layer "B.Cu")
		(at 128.55575 -51.2572 180)
		(property "Reference" "R1263"
			(at -0.67945 -1.06807 0)
			(unlocked yes)
			(layer "B.SilkS")
			(effects
				(font
					(size 0.7874 0.5842)
					(thickness 0.1524)
				)
				(justify left mirror)
			)
		)
		(property "Value" ""
			(at 0 0 0)
			(layer "B.Fab")
			(effects
				(font
					(size 1.27 1.27)
				)
				(justify mirror)
			)
		)
		(duplicate_pad_numbers_are_jumpers no)
		(fp_line
			(start 0.7874 0.4064)
			(end 0.7874 -0.4064)
			(stroke
				(width 0.1524)
				(type default)
			)
			(layer "B.SilkS")
		)
		(fp_line
			(start 0.7874 -0.4064)
			(end -0.7874 -0.4064)
			(stroke
				(width 0.1524)
				(type default)
			)
			(layer "B.SilkS")
		)
		(fp_line
			(start -0.7874 0.4064)
			(end 0.7874 0.4064)
			(stroke
				(width 0.1524)
				(type default)
			)
			(layer "B.SilkS")
		)
		(fp_line
			(start -0.7874 -0.4064)
			(end -0.7874 0.4064)
			(stroke
				(width 0.1524)
				(type default)
			)
			(layer "B.SilkS")
		)
		(fp_poly
			(pts
				(xy 0.508 0.2794) (xy 0.508 0.2286) (xy 0.635 0.2286) (xy 0.635 -0.254) (xy 0.5334 -0.254) (xy 0.5334 -0.2794)
				(xy -0.5334 -0.2794) (xy -0.5334 -0.254) (xy -0.635 -0.254) (xy -0.635 0.254) (xy -0.5334 0.254)
				(xy -0.5334 0.2794)
			)
			(stroke
				(width 0)
				(type default)
			)
			(fill no)
			(layer "B.CrtYd")
		)
		(pad "1" smd rect
			(at -0.40005 0)
			(size 0.4572 0.508)
			(layers "B.Cu" "B.Mask" "B.Paste")
			(net "P5V_NODE1")
		)
		(pad "2" smd rect
			(at 0.40005 0)
			(size 0.4572 0.508)
			(layers "B.Cu" "B.Mask" "B.Paste")
			(net "UART_RI_P3_N")
		)
	)
)
